(kicad_pcb
	(version 20241229)
	(generator "pcbnew")
	(generator_version "9.0")
	(general
		(thickness 1.62)
		(legacy_teardrops no)
	)
	(paper "A4")
	(title_block
		(title "OCuLink to 10GbE adapter")
		(date "2026-02-23")
		(rev "1.1.0")
		(company "Antmicro Ltd")
		(comment 1 "www.antmicro.com")
		(comment 9 "footprints 435-439 of 510")
	)
	(layers
		(0 "F.Cu" signal)
		(4 "In1.Cu" signal)
		(6 "In2.Cu" signal)
		(8 "In3.Cu" signal)
		(10 "In4.Cu" signal)
		(12 "In5.Cu" signal)
		(14 "In6.Cu" signal)
		(2 "B.Cu" signal)
		(9 "F.Adhes" user "F.Adhesive")
		(11 "B.Adhes" user "B.Adhesive")
		(13 "F.Paste" user)
		(15 "B.Paste" user)
		(5 "F.SilkS" user "F.Silkscreen")
		(7 "B.SilkS" user "B.Silkscreen")
		(1 "F.Mask" user)
		(3 "B.Mask" user)
		(17 "Dwgs.User" user "User.Drawings")
		(19 "Cmts.User" user "User.Comments")
		(21 "Eco1.User" user "User.Eco1")
		(23 "Eco2.User" user "User.Eco2")
		(25 "Edge.Cuts" user)
		(27 "Margin" user)
		(31 "F.CrtYd" user "F.Courtyard")
		(29 "B.CrtYd" user "B.Courtyard")
		(35 "F.Fab" user)
		(33 "B.Fab" user)
	)
	(footprint "antmicro-footprints:C_0402_1005Metric"
		(layer "B.Cu")
		(at 81 108.375)
		(descr "Capacitor SMD 0402")
		(tags "capacitor SMD 0402")
		(property "Reference" "C178"
			(at -0.97 11.475 0)
			(layer "B.SilkS")
			(effects
				(font
					(size 0.7 0.7)
					(thickness 0.15)
				)
				(justify right top mirror)
			)
		)
		(property "Value" "C_1u_25V_0402"
			(at -1.022927 -2.155213 0)
			(layer "B.Fab")
			(hide yes)
			(effects
				(font
					(size 0.7 0.7)
					(thickness 0.15)
				)
				(justify right top mirror)
			)
		)
		(property "Datasheet" "https://www.murata.com/products/productdetail?partno=GRM155R61E105KE11%23"
			(at 0 0 0)
			(layer "B.Fab")
			(hide yes)
			(effects
				(font
					(size 1.27 1.27)
					(thickness 0.15)
				)
				(justify mirror)
			)
		)
		(property "Description" "SMD Multilayer Ceramic Capacitor, 1 µF, 25 V, 0402 [1005 Metric], ± 10%, X5R, GRM Series"
			(at 0 0 0)
			(layer "B.Fab")
			(hide yes)
			(effects
				(font
					(size 1.27 1.27)
					(thickness 0.15)
				)
				(justify mirror)
			)
		)
		(property "MPN" "GRM155R61E105KE11J"
			(at 0 0 0)
			(unlocked yes)
			(layer "B.Fab")
			(hide yes)
			(effects
				(font
					(size 1 1)
					(thickness 0.15)
				)
				(justify mirror)
			)
		)
		(property "Manufacturer" "Murata"
			(at 0 0 0)
			(unlocked yes)
			(layer "B.Fab")
			(hide yes)
			(effects
				(font
					(size 1 1)
					(thickness 0.15)
				)
				(justify mirror)
			)
		)
		(property "License" "Apache-2.0"
			(at 0 0 0)
			(unlocked yes)
			(layer "B.Fab")
			(hide yes)
			(effects
				(font
					(size 1 1)
					(thickness 0.15)
				)
				(justify mirror)
			)
		)
		(property "Author" "Antmicro"
			(at 0 0 0)
			(unlocked yes)
			(layer "B.Fab")
			(hide yes)
			(effects
				(font
					(size 1 1)
					(thickness 0.15)
				)
				(justify mirror)
			)
		)
		(property "Val" "1u"
			(at 0 0 0)
			(unlocked yes)
			(layer "B.Fab")
			(hide yes)
			(effects
				(font
					(size 1 1)
					(thickness 0.15)
				)
				(justify mirror)
			)
		)
		(property "Voltage" "25V"
			(at 0 0 0)
			(unlocked yes)
			(layer "B.Fab")
			(hide yes)
			(effects
				(font
					(size 1 1)
					(thickness 0.15)
				)
				(justify mirror)
			)
		)
		(property "Dielectric" "X5R"
			(at 0 0 0)
			(unlocked yes)
			(layer "B.Fab")
			(hide yes)
			(effects
				(font
					(size 1 1)
					(thickness 0.15)
				)
				(justify mirror)
			)
		)
		(sheetname "/X710-AT2 power/")
		(sheetfile "x710-at2-power.kicad_sch")
		(attr smd)
		(fp_rect
			(start -0.925 0.47)
			(end 0.925 -0.47)
			(stroke
				(width 0.05)
				(type default)
			)
			(fill no)
			(layer "B.CrtYd")
		)
		(fp_line
			(start -0.494 -0.248)
			(end -0.494 0.25)
			(stroke
				(width 0.15)
				(type solid)
			)
			(layer "B.Fab")
		)
		(fp_line
			(start -0.494 0.25)
			(end 0.504 0.25)
			(stroke
				(width 0.15)
				(type solid)
			)
			(layer "B.Fab")
		)
		(fp_line
			(start 0.504 -0.248)
			(end -0.494 -0.248)
			(stroke
				(width 0.15)
				(type solid)
			)
			(layer "B.Fab")
		)
		(fp_line
			(start 0.504 0.25)
			(end 0.504 -0.248)
			(stroke
				(width 0.15)
				(type solid)
			)
			(layer "B.Fab")
		)
		(pad "1" smd roundrect
			(at -0.48 0)
			(size 0.59 0.64)
			(layers "B.Cu" "B.Mask" "B.Paste")
			(roundrect_rratio 0.25)
			(net 28 "GND")
			(pintype "passive")
		)
		(pad "2" smd roundrect
			(at 0.48 0)
			(size 0.59 0.64)
			(layers "B.Cu" "B.Mask" "B.Paste")
			(roundrect_rratio 0.25)
			(net 14 "P1_AVDDL")
			(pintype "passive")
		)
	)
	(footprint "antmicro-footprints:C_Pol_EIA-D"
		(layer "B.Cu")
		(at 65.25 107.55 90)
		(property "Reference" "C156"
			(at -1.45 -3.25 90)
			(layer "B.SilkS")
			(effects
				(font
					(size 0.7 0.7)
					(thickness 0.15)
				)
				(justify right top mirror)
			)
		)
		(property "Value" "C_Pol_470u_6.3V_Vishay-TR3-D"
			(at 0 -3.4 90)
			(layer "B.Fab")
			(hide yes)
			(effects
				(font
					(size 0.7 0.7)
					(thickness 0.15)
				)
				(justify right top mirror)
			)
		)
		(property "Datasheet" "https://www.vishay.com/docs/40080/tr3.pdf"
			(at 0 0 90)
			(layer "B.Fab")
			(hide yes)
			(effects
				(font
					(size 1.27 1.27)
					(thickness 0.15)
				)
				(justify mirror)
			)
		)
		(property "Description" "470 µF Molded Tantalum Capacitors 6.3 V 2917 (7343 Metric) 200mOhm"
			(at 0 0 90)
			(layer "B.Fab")
			(hide yes)
			(effects
				(font
					(size 1.27 1.27)
					(thickness 0.15)
				)
				(justify mirror)
			)
		)
		(property "Val" "470u"
			(at 0 0 90)
			(unlocked yes)
			(layer "B.Fab")
			(hide yes)
			(effects
				(font
					(size 1 1)
					(thickness 0.15)
				)
				(justify mirror)
			)
		)
		(property "MPN" "TR3D477M6R3C0200"
			(at 0 0 90)
			(unlocked yes)
			(layer "B.Fab")
			(hide yes)
			(effects
				(font
					(size 1 1)
					(thickness 0.15)
				)
				(justify mirror)
			)
		)
		(property "Manufacturer" "Vishay"
			(at 0 0 90)
			(unlocked yes)
			(layer "B.Fab")
			(hide yes)
			(effects
				(font
					(size 1 1)
					(thickness 0.15)
				)
				(justify mirror)
			)
		)
		(property "License" "Apache-2.0"
			(at 0 0 90)
			(unlocked yes)
			(layer "B.Fab")
			(hide yes)
			(effects
				(font
					(size 1 1)
					(thickness 0.15)
				)
				(justify mirror)
			)
		)
		(property "Author" "Antmicro"
			(at 0 0 90)
			(unlocked yes)
			(layer "B.Fab")
			(hide yes)
			(effects
				(font
					(size 1 1)
					(thickness 0.15)
				)
				(justify mirror)
			)
		)
		(property "Voltage" "6.3V"
			(at 0 0 90)
			(unlocked yes)
			(layer "B.Fab")
			(hide yes)
			(effects
				(font
					(size 1 1)
					(thickness 0.15)
				)
				(justify mirror)
			)
		)
		(property "Dielectric" "template_dielectric"
			(at 0 0 90)
			(unlocked yes)
			(layer "B.Fab")
			(hide yes)
			(effects
				(font
					(size 1 1)
					(thickness 0.15)
				)
				(justify mirror)
			)
		)
		(sheetname "/X710-AT2 power/")
		(sheetfile "x710-at2-power.kicad_sch")
		(attr smd)
		(fp_line
			(start 3.6 -2.2)
			(end -3.58 -2.2)
			(stroke
				(width 0.15)
				(type solid)
			)
			(layer "B.SilkS")
		)
		(fp_line
			(start -3.58 -2.2)
			(end -3.58 -1.6)
			(stroke
				(width 0.15)
				(type solid)
			)
			(layer "B.SilkS")
		)
		(fp_line
			(start 3.6 -1.6)
			(end 3.6 -2.2)
			(stroke
				(width 0.15)
				(type solid)
			)
			(layer "B.SilkS")
		)
		(fp_line
			(start -3.58 1.6)
			(end -3.58 2.2)
			(stroke
				(width 0.15)
				(type solid)
			)
			(layer "B.SilkS")
		)
		(fp_line
			(start -4.3 1.825)
			(end -3.9 1.825)
			(stroke
				(width 0.12)
				(type solid)
			)
			(layer "B.SilkS")
		)
		(fp_line
			(start -4.1 2.025)
			(end -4.1 1.625)
			(stroke
				(width 0.12)
				(type solid)
			)
			(layer "B.SilkS")
		)
		(fp_line
			(start 3.6 2.2)
			(end 3.6 1.6)
			(stroke
				(width 0.15)
				(type solid)
			)
			(layer "B.SilkS")
		)
		(fp_line
			(start -3.58 2.2)
			(end 3.6 2.2)
			(stroke
				(width 0.15)
				(type solid)
			)
			(layer "B.SilkS")
		)
		(fp_line
			(start 3.77 -2.4)
			(end -3.77 -2.4)
			(stroke
				(width 0.05)
				(type solid)
			)
			(layer "B.CrtYd")
		)
		(fp_line
			(start -3.77 -2.4)
			(end -3.77 -1.51)
			(stroke
				(width 0.05)
				(type solid)
			)
			(layer "B.CrtYd")
		)
		(fp_line
			(start 4.505 -1.51)
			(end 3.77 -1.51)
			(stroke
				(width 0.05)
				(type solid)
			)
			(layer "B.CrtYd")
		)
		(fp_line
			(start 3.77 -1.51)
			(end 3.77 -2.4)
			(stroke
				(width 0.05)
				(type solid)
			)
			(layer "B.CrtYd")
		)
		(fp_line
			(start -3.77 -1.51)
			(end -4.505 -1.51)
			(stroke
				(width 0.05)
				(type solid)
			)
			(layer "B.CrtYd")
		)
		(fp_line
			(start -4.505 -1.51)
			(end -4.505 1.5)
			(stroke
				(width 0.05)
				(type solid)
			)
			(layer "B.CrtYd")
		)
		(fp_line
			(start -3.775 1.5)
			(end -4.505 1.5)
			(stroke
				(width 0.05)
				(type solid)
			)
			(layer "B.CrtYd")
		)
		(fp_line
			(start 4.505 1.51)
			(end 4.505 -1.5)
			(stroke
				(width 0.05)
				(type solid)
			)
			(layer "B.CrtYd")
		)
		(fp_line
			(start 3.77 1.51)
			(end 4.505 1.51)
			(stroke
				(width 0.05)
				(type solid)
			)
			(layer "B.CrtYd")
		)
		(fp_line
			(start 3.77 2.4)
			(end 3.77 1.51)
			(stroke
				(width 0.05)
				(type solid)
			)
			(layer "B.CrtYd")
		)
		(fp_line
			(start -3.775 2.4)
			(end -3.775 1.5)
			(stroke
				(width 0.05)
				(type solid)
			)
			(layer "B.CrtYd")
		)
		(fp_line
			(start -3.775 2.4)
			(end 3.77 2.4)
			(stroke
				(width 0.05)
				(type solid)
			)
			(layer "B.CrtYd")
		)
		(fp_rect
			(start -3.65 2.15)
			(end 3.65 -2.15)
			(stroke
				(width 0.15)
				(type solid)
			)
			(fill no)
			(layer "B.Fab")
		)
		(pad "1" smd roundrect
			(at -3.1 0 90)
			(size 2.31 2.52)
			(layers "B.Cu" "B.Mask" "B.Paste")
			(roundrect_rratio 0.1)
			(net 302 "+1V0")
			(pintype "passive")
		)
		(pad "2" smd roundrect
			(at 3.1 0 90)
			(size 2.31 2.52)
			(layers "B.Cu" "B.Mask" "B.Paste")
			(roundrect_rratio 0.1)
			(net 28 "GND")
			(pintype "passive")
		)
	)
	(footprint "antmicro-footprints:C_0402_1005Metric"
		(layer "B.Cu")
		(at 83.24 105.08 90)
		(descr "Capacitor SMD 0402")
		(tags "capacitor SMD 0402")
		(property "Reference" "C103"
			(at -1.29 0.6 90)
			(layer "B.SilkS")
			(effects
				(font
					(size 0.7 0.7)
					(thickness 0.15)
				)
				(justify right top mirror)
			)
		)
		(property "Value" "C_1u_25V_0402"
			(at -1.022927 -2.155213 90)
			(layer "B.Fab")
			(hide yes)
			(effects
				(font
					(size 0.7 0.7)
					(thickness 0.15)
				)
				(justify right top mirror)
			)
		)
		(property "Datasheet" "https://www.murata.com/products/productdetail?partno=GRM155R61E105KE11%23"
			(at 0 0 90)
			(layer "B.Fab")
			(hide yes)
			(effects
				(font
					(size 1.27 1.27)
					(thickness 0.15)
				)
				(justify mirror)
			)
		)
		(property "Description" "SMD Multilayer Ceramic Capacitor, 1 µF, 25 V, 0402 [1005 Metric], ± 10%, X5R, GRM Series"
			(at 0 0 90)
			(layer "B.Fab")
			(hide yes)
			(effects
				(font
					(size 1.27 1.27)
					(thickness 0.15)
				)
				(justify mirror)
			)
		)
		(property "MPN" "GRM155R61E105KE11J"
			(at 0 0 90)
			(unlocked yes)
			(layer "B.Fab")
			(hide yes)
			(effects
				(font
					(size 1 1)
					(thickness 0.15)
				)
				(justify mirror)
			)
		)
		(property "Manufacturer" "Murata"
			(at 0 0 90)
			(unlocked yes)
			(layer "B.Fab")
			(hide yes)
			(effects
				(font
					(size 1 1)
					(thickness 0.15)
				)
				(justify mirror)
			)
		)
		(property "License" "Apache-2.0"
			(at 0 0 90)
			(unlocked yes)
			(layer "B.Fab")
			(hide yes)
			(effects
				(font
					(size 1 1)
					(thickness 0.15)
				)
				(justify mirror)
			)
		)
		(property "Author" "Antmicro"
			(at 0 0 90)
			(unlocked yes)
			(layer "B.Fab")
			(hide yes)
			(effects
				(font
					(size 1 1)
					(thickness 0.15)
				)
				(justify mirror)
			)
		)
		(property "Val" "1u"
			(at 0 0 90)
			(unlocked yes)
			(layer "B.Fab")
			(hide yes)
			(effects
				(font
					(size 1 1)
					(thickness 0.15)
				)
				(justify mirror)
			)
		)
		(property "Voltage" "25V"
			(at 0 0 90)
			(unlocked yes)
			(layer "B.Fab")
			(hide yes)
			(effects
				(font
					(size 1 1)
					(thickness 0.15)
				)
				(justify mirror)
			)
		)
		(property "Dielectric" "X5R"
			(at 0 0 90)
			(unlocked yes)
			(layer "B.Fab")
			(hide yes)
			(effects
				(font
					(size 1 1)
					(thickness 0.15)
				)
				(justify mirror)
			)
		)
		(sheetname "/X710-AT2 power/")
		(sheetfile "x710-at2-power.kicad_sch")
		(attr smd)
		(fp_rect
			(start -0.925 0.47)
			(end 0.925 -0.47)
			(stroke
				(width 0.05)
				(type default)
			)
			(fill no)
			(layer "B.CrtYd")
		)
		(fp_line
			(start 0.504 -0.248)
			(end -0.494 -0.248)
			(stroke
				(width 0.15)
				(type solid)
			)
			(layer "B.Fab")
		)
		(fp_line
			(start -0.494 -0.248)
			(end -0.494 0.25)
			(stroke
				(width 0.15)
				(type solid)
			)
			(layer "B.Fab")
		)
		(fp_line
			(start 0.504 0.25)
			(end 0.504 -0.248)
			(stroke
				(width 0.15)
				(type solid)
			)
			(layer "B.Fab")
		)
		(fp_line
			(start -0.494 0.25)
			(end 0.504 0.25)
			(stroke
				(width 0.15)
				(type solid)
			)
			(layer "B.Fab")
		)
		(pad "1" smd roundrect
			(at -0.48 0 90)
			(size 0.59 0.64)
			(layers "B.Cu" "B.Mask" "B.Paste")
			(roundrect_rratio 0.25)
			(net 28 "GND")
			(pintype "passive")
		)
		(pad "2" smd roundrect
			(at 0.48 0 90)
			(size 0.59 0.64)
			(layers "B.Cu" "B.Mask" "B.Paste")
			(roundrect_rratio 0.25)
			(net 18 "+1V88")
			(pintype "passive")
		)
	)
	(footprint "antmicro-footprints:C_0402_1005Metric"
		(layer "B.Cu")
		(at 86.225 94.6 90)
		(descr "Capacitor SMD 0402")
		(tags "capacitor SMD 0402")
		(property "Reference" "C93"
			(at 12.5 -0.462343 90)
			(layer "B.SilkS")
			(effects
				(font
					(size 0.7 0.7)
					(thickness 0.15)
				)
				(justify right top mirror)
			)
		)
		(property "Value" "C_1u_25V_0402"
			(at -1.022927 -2.155213 90)
			(layer "B.Fab")
			(hide yes)
			(effects
				(font
					(size 0.7 0.7)
					(thickness 0.15)
				)
				(justify right top mirror)
			)
		)
		(property "Datasheet" "https://www.murata.com/products/productdetail?partno=GRM155R61E105KE11%23"
			(at 0 0 90)
			(layer "B.Fab")
			(hide yes)
			(effects
				(font
					(size 1.27 1.27)
					(thickness 0.15)
				)
				(justify mirror)
			)
		)
		(property "Description" "SMD Multilayer Ceramic Capacitor, 1 µF, 25 V, 0402 [1005 Metric], ± 10%, X5R, GRM Series"
			(at 0 0 90)
			(layer "B.Fab")
			(hide yes)
			(effects
				(font
					(size 1.27 1.27)
					(thickness 0.15)
				)
				(justify mirror)
			)
		)
		(property "MPN" "GRM155R61E105KE11J"
			(at 0 0 90)
			(unlocked yes)
			(layer "B.Fab")
			(hide yes)
			(effects
				(font
					(size 1 1)
					(thickness 0.15)
				)
				(justify mirror)
			)
		)
		(property "Manufacturer" "Murata"
			(at 0 0 90)
			(unlocked yes)
			(layer "B.Fab")
			(hide yes)
			(effects
				(font
					(size 1 1)
					(thickness 0.15)
				)
				(justify mirror)
			)
		)
		(property "License" "Apache-2.0"
			(at 0 0 90)
			(unlocked yes)
			(layer "B.Fab")
			(hide yes)
			(effects
				(font
					(size 1 1)
					(thickness 0.15)
				)
				(justify mirror)
			)
		)
		(property "Author" "Antmicro"
			(at 0 0 90)
			(unlocked yes)
			(layer "B.Fab")
			(hide yes)
			(effects
				(font
					(size 1 1)
					(thickness 0.15)
				)
				(justify mirror)
			)
		)
		(property "Val" "1u"
			(at 0 0 90)
			(unlocked yes)
			(layer "B.Fab")
			(hide yes)
			(effects
				(font
					(size 1 1)
					(thickness 0.15)
				)
				(justify mirror)
			)
		)
		(property "Voltage" "25V"
			(at 0 0 90)
			(unlocked yes)
			(layer "B.Fab")
			(hide yes)
			(effects
				(font
					(size 1 1)
					(thickness 0.15)
				)
				(justify mirror)
			)
		)
		(property "Dielectric" "X5R"
			(at 0 0 90)
			(unlocked yes)
			(layer "B.Fab")
			(hide yes)
			(effects
				(font
					(size 1 1)
					(thickness 0.15)
				)
				(justify mirror)
			)
		)
		(sheetname "/X710-AT2 power/")
		(sheetfile "x710-at2-power.kicad_sch")
		(attr smd)
		(fp_rect
			(start -0.925 0.47)
			(end 0.925 -0.47)
			(stroke
				(width 0.05)
				(type default)
			)
			(fill no)
			(layer "B.CrtYd")
		)
		(fp_line
			(start 0.504 -0.248)
			(end -0.494 -0.248)
			(stroke
				(width 0.15)
				(type solid)
			)
			(layer "B.Fab")
		)
		(fp_line
			(start -0.494 -0.248)
			(end -0.494 0.25)
			(stroke
				(width 0.15)
				(type solid)
			)
			(layer "B.Fab")
		)
		(fp_line
			(start 0.504 0.25)
			(end 0.504 -0.248)
			(stroke
				(width 0.15)
				(type solid)
			)
			(layer "B.Fab")
		)
		(fp_line
			(start -0.494 0.25)
			(end 0.504 0.25)
			(stroke
				(width 0.15)
				(type solid)
			)
			(layer "B.Fab")
		)
		(pad "1" smd roundrect
			(at -0.48 0 90)
			(size 0.59 0.64)
			(layers "B.Cu" "B.Mask" "B.Paste")
			(roundrect_rratio 0.25)
			(net 28 "GND")
			(pintype "passive")
		)
		(pad "2" smd roundrect
			(at 0.48 0 90)
			(size 0.59 0.64)
			(layers "B.Cu" "B.Mask" "B.Paste")
			(roundrect_rratio 0.25)
			(net 1 "VCCA")
			(pintype "passive")
		)
	)
	(footprint "antmicro-footprints:R_0402_1005Metric"
		(layer "B.Cu")
		(at 99.16 89.214 180)
		(descr "Resistor SMD 0402")
		(tags "resistor SMD 0402")
		(property "Reference" "R122"
			(at 0.85 -0.436 0)
			(layer "B.SilkS")
			(effects
				(font
					(size 0.7 0.7)
					(thickness 0.15)
				)
				(justify left bottom mirror)
			)
		)
		(property "Value" "R_0R_0402"
			(at -1.011843 -1.772047 0)
			(layer "B.Fab")
			(hide yes)
			(effects
				(font
					(size 0.7 0.7)
					(thickness 0.15)
				)
				(justify left bottom mirror)
			)
		)
		(property "Datasheet" "https://industrial.panasonic.com/cdbs/www-data/pdf/RDA0000/AOA0000C301.pdf"
			(at 0 0 0)
			(layer "B.Fab")
			(hide yes)
			(effects
				(font
					(size 1.27 1.27)
					(thickness 0.15)
				)
				(justify mirror)
			)
		)
		(property "Description" "SMD Chip Resistor, Jumper, 0 ohm, 100 mW, 0402 [1005 Metric], Thick Film, General Purpose"
			(at 0 0 0)
			(layer "B.Fab")
			(hide yes)
			(effects
				(font
					(size 1.27 1.27)
					(thickness 0.15)
				)
				(justify mirror)
			)
		)
		(property "MPN" "ERJ2GE0R00X"
			(at 0 0 0)
			(unlocked yes)
			(layer "B.Fab")
			(hide yes)
			(effects
				(font
					(size 1 1)
					(thickness 0.15)
				)
				(justify mirror)
			)
		)
		(property "Manufacturer" "Panasonic"
			(at 0 0 0)
			(unlocked yes)
			(layer "B.Fab")
			(hide yes)
			(effects
				(font
					(size 1 1)
					(thickness 0.15)
				)
				(justify mirror)
			)
		)
		(property "License" "Apache-2.0"
			(at 0 0 0)
			(unlocked yes)
			(layer "B.Fab")
			(hide yes)
			(effects
				(font
					(size 1 1)
					(thickness 0.15)
				)
				(justify mirror)
			)
		)
		(property "Author" "Antmicro"
			(at 0 0 0)
			(unlocked yes)
			(layer "B.Fab")
			(hide yes)
			(effects
				(font
					(size 1 1)
					(thickness 0.15)
				)
				(justify mirror)
			)
		)
		(property "Val" "0R"
			(at 0 0 0)
			(unlocked yes)
			(layer "B.Fab")
			(hide yes)
			(effects
				(font
					(size 1 1)
					(thickness 0.15)
				)
				(justify mirror)
			)
		)
		(property "Tolerance" "~"
			(at 0 0 0)
			(unlocked yes)
			(layer "B.Fab")
			(hide yes)
			(effects
				(font
					(size 1 1)
					(thickness 0.15)
				)
				(justify mirror)
			)
		)
		(property "Current" "1A"
			(at 0 0 0)
			(unlocked yes)
			(layer "B.Fab")
			(hide yes)
			(effects
				(font
					(size 1 1)
					(thickness 0.15)
				)
				(justify mirror)
			)
		)
		(sheetname "/X710-AT2 PCIe/")
		(sheetfile "x710-at2-pcie.kicad_sch")
		(attr smd exclude_from_pos_files exclude_from_bom dnp)
		(fp_rect
			(start -0.925 0.47)
			(end 0.925 -0.47)
			(stroke
				(width 0.05)
				(type default)
			)
			(fill no)
			(layer "B.CrtYd")
		)
		(fp_rect
			(start -0.5 0.25)
			(end 0.5 -0.25)
			(stroke
				(width 0.15)
				(type solid)
			)
			(fill no)
			(layer "B.Fab")
		)
		(pad "1" smd roundrect
			(at -0.48 0 180)
			(size 0.59 0.64)
			(layers "B.Cu" "B.Mask" "B.Paste")
			(roundrect_rratio 0.25)
			(net 406 "/X710-AT2 PCIe/GEN_F_CLK-")
			(pintype "passive")
		)
		(pad "2" smd roundrect
			(at 0.48 0 180)
			(size 0.59 0.64)
			(layers "B.Cu" "B.Mask" "B.Paste")
			(roundrect_rratio 0.25)
			(net 403 "/X710-AT2 PCIe/CLK-")
			(pintype "passive")
		)
	)
)
